# TIMECARD (Time Appliance Project (Time Card)) — schematic netlist excerpt (pin names and nets, part order shuffled) for the footprints in the layout excerpt that follows; sources: Cadence DE-HDL packaged netlist, KiCad conversion of R4006-B0001-02_R01.brd

R149  RESISTOR  4.7KOHM 1%  pkg SMC_0402R_H016  page 16 : \1\ = XP3R3V_FPGA ; \2\ = UNNAMED_5_PCA9546APWTSSOP16_I33
R441  RESISTOR  10KOHM 1%  pkg SMC_0402R_H016  page 13 : \1\ = FPGA_IN_MAC_PPS_OUTN ; \2\ = SG

(kicad_pcb
	(version 20260206)
	(generator "pcbnew")
	(generator_version "10.0")
	(general
		(thickness 1.6)
		(legacy_teardrops no)
	)
	(paper "A4")
	(title_block
		(title "timecard-production-celestica-r4006 — R4006-B0001-02_R01.brd")
		(comment 1 "Time Appliance Project (Time Card) / footprints 920-921 of 1113")
	)
	(layers
		(0 "F.Cu" signal "TOP")
		(4 "In1.Cu" signal "L02_GND1")
		(6 "In2.Cu" signal "L03_SIG1")
		(8 "In3.Cu" signal "L04_GND2")
		(10 "In4.Cu" signal "L05_VCC1")
		(12 "In5.Cu" signal "L06_VCC2")
		(14 "In6.Cu" signal "L07_GND3")
		(16 "In7.Cu" signal "L08_SIG2")
		(18 "In8.Cu" signal "L09_GND4")
		(2 "B.Cu" signal "BOTTOM")
		(9 "F.Adhes" user "F.Adhesive")
		(11 "B.Adhes" user "B.Adhesive")
		(13 "F.Paste" user "Package Geometry/Pastemask Top")
		(15 "B.Paste" user "Package Geometry/Pastemask Bottom")
		(5 "F.SilkS" user "Ref Des/Silkscreen Top")
		(7 "B.SilkS" user "Ref Des/Silkscreen Bottom")
		(1 "F.Mask" user "Board Geometry/Soldermask Top")
		(3 "B.Mask" user "Board Geometry/Soldermask Bottom")
		(17 "Dwgs.User" user "User.Drawings")
		(19 "Cmts.User" user "User.Comments")
		(21 "Eco1.User" user "User.Eco1")
		(23 "Eco2.User" user "User.Eco2")
		(25 "Edge.Cuts" user "Board Geometry/Outline")
		(27 "Margin" user)
		(31 "F.CrtYd" user "Package Geometry/Place Bound Top")
		(29 "B.CrtYd" user "Package Geometry/Place Bound Bottom")
		(35 "F.Fab" user "Ref Des/Assembly Top")
		(33 "B.Fab" user "Ref Des/Assembly Bottom")
	)
	(footprint ""
		(layer "B.Cu")
		(at 83.2358 -81.407 180)
		(property "Reference" "R149"
			(at 0.1778 -2.19837 0)
			(unlocked yes)
			(layer "B.SilkS")
			(effects
				(font
					(size 0.7874 0.5842)
					(thickness 0.1524)
				)
				(justify mirror)
			)
		)
		(property "Value" "VAL*"
			(at -0.02032 2.13233 180)
			(unlocked yes)
			(layer "B.Fab")
			(hide yes)
			(effects
				(font
					(size 0.7874 0.5842)
					(thickness 0.1524)
				)
				(justify mirror)
			)
		)
		(property "Tolerance" "TOL*"
			(at -0.044704 3.05435 180)
			(unlocked yes)
			(layer "Cmts.User")
			(hide yes)
			(effects
				(font
					(size 0.7874 0.5842)
					(thickness 0.1524)
				)
				(justify mirror)
			)
		)
		(property "User Part Number" "PARTNUM*"
			(at -0.02032 4.024884 180)
			(unlocked yes)
			(layer "Cmts.User")
			(hide yes)
			(effects
				(font
					(size 0.7874 0.5842)
					(thickness 0.1524)
				)
				(justify mirror)
			)
		)
		(property "Device Type" "RESISTOR-G155-14701-01,4.7KOHMA"
			(at -0.008382 1.210564 180)
			(unlocked yes)
			(layer "B.Fab")
			(hide yes)
			(effects
				(font
					(size 0.7874 0.5842)
					(thickness 0.1524)
				)
				(justify mirror)
			)
		)
		(duplicate_pad_numbers_are_jumpers no)
		(fp_line
			(start 1.143 0.5588)
			(end -1.143 0.5588)
			(stroke
				(width 0.1)
				(type default)
			)
			(layer "B.SilkS")
		)
		(fp_line
			(start 1.143 -0.5588)
			(end 1.143 0.5588)
			(stroke
				(width 0.1)
				(type default)
			)
			(layer "B.SilkS")
		)
		(fp_line
			(start -1.143 0.5588)
			(end -1.143 -0.5588)
			(stroke
				(width 0.1)
				(type default)
			)
			(layer "B.SilkS")
		)
		(fp_line
			(start -1.143 -0.5588)
			(end 1.143 -0.5588)
			(stroke
				(width 0.1)
				(type default)
			)
			(layer "B.SilkS")
		)
		(fp_rect
			(start -1.143 0.5588)
			(end 1.143 -0.5588)
			(stroke
				(width 0)
				(type default)
			)
			(fill no)
			(layer "B.CrtYd")
		)
		(fp_line
			(start 0.508 0.3048)
			(end -0.508 0.3048)
			(stroke
				(width 0.1)
				(type default)
			)
			(layer "B.Fab")
		)
		(fp_line
			(start 0.508 -0.3048)
			(end 0.508 0.3048)
			(stroke
				(width 0.1)
				(type default)
			)
			(layer "B.Fab")
		)
		(fp_line
			(start -0.508 0.3048)
			(end -0.508 -0.3048)
			(stroke
				(width 0.1)
				(type default)
			)
			(layer "B.Fab")
		)
		(fp_line
			(start -0.508 -0.3048)
			(end 0.508 -0.3048)
			(stroke
				(width 0.1)
				(type default)
			)
			(layer "B.Fab")
		)
		(pad "1" smd rect
			(at 0.5334 0)
			(size 0.7112 0.6096)
			(layers "B.Cu" "B.Mask" "B.Paste")
			(net "XP3R3V_FPGA")
		)
		(pad "2" smd rect
			(at -0.5334 0)
			(size 0.7112 0.6096)
			(layers "B.Cu" "B.Mask" "B.Paste")
			(net "UNNAMED_5_PCA9546APWTSSOP16_I33")
		)
		(zone
			(layer "B.Cu")
			(hatch none 0.5)
			(connect_pads
				(clearance 0)
			)
			(min_thickness 0.25)
			(keepout
				(tracks allowed)
				(vias not_allowed)
				(pads allowed)
				(copperpour not_allowed)
				(footprints allowed)
			)
			(placement
				(enabled no)
				(sheetname "")
			)
			(fill
				(thermal_gap 0.5)
				(thermal_bridge_width 0.5)
				(island_removal_mode 0)
			)
			(polygon
				(pts
					(xy 83.312 -81.7118) (xy 83.1596 -81.7118) (xy 83.1596 -81.1022) (xy 83.312 -81.1022)
				)
			)
		)
	)
	(footprint ""
		(layer "B.Cu")
		(at 116.459 -29.464 90)
		(property "Reference" "R441"
			(at -3.429 -0.03937 270)
			(unlocked yes)
			(layer "B.SilkS")
			(effects
				(font
					(size 0.7874 0.5842)
					(thickness 0.1524)
				)
				(justify mirror)
			)
		)
		(property "Value" "VAL*"
			(at -0.02032 2.13233 90)
			(unlocked yes)
			(layer "B.Fab")
			(hide yes)
			(effects
				(font
					(size 0.7874 0.5842)
					(thickness 0.1524)
				)
				(justify mirror)
			)
		)
		(property "Tolerance" "TOL*"
			(at -0.044704 3.05435 90)
			(unlocked yes)
			(layer "Cmts.User")
			(hide yes)
			(effects
				(font
					(size 0.7874 0.5842)
					(thickness 0.1524)
				)
				(justify mirror)
			)
		)
		(property "User Part Number" "PARTNUM*"
			(at -0.02032 4.024884 90)
			(unlocked yes)
			(layer "Cmts.User")
			(hide yes)
			(effects
				(font
					(size 0.7874 0.5842)
					(thickness 0.1524)
				)
				(justify mirror)
			)
		)
		(property "Device Type" "RESISTOR-G155-11002-01,10KOHM,A"
			(at -0.008382 1.210564 90)
			(unlocked yes)
			(layer "B.Fab")
			(hide yes)
			(effects
				(font
					(size 0.7874 0.5842)
					(thickness 0.1524)
				)
				(justify mirror)
			)
		)
		(duplicate_pad_numbers_are_jumpers no)
		(fp_line
			(start 1.143 -0.5588)
			(end 1.143 0.5588)
			(stroke
				(width 0.1)
				(type default)
			)
			(layer "B.SilkS")
		)
		(fp_line
			(start -1.143 -0.5588)
			(end 1.143 -0.5588)
			(stroke
				(width 0.1)
				(type default)
			)
			(layer "B.SilkS")
		)
		(fp_line
			(start 1.143 0.5588)
			(end -1.143 0.5588)
			(stroke
				(width 0.1)
				(type default)
			)
			(layer "B.SilkS")
		)
		(fp_line
			(start -1.143 0.5588)
			(end -1.143 -0.5588)
			(stroke
				(width 0.1)
				(type default)
			)
			(layer "B.SilkS")
		)
		(fp_poly
			(pts
				(xy 1.143 0.5588) (xy -1.143 0.5588) (xy -1.143 -0.5588) (xy 1.143 -0.5588)
			)
			(stroke
				(width 0)
				(type default)
			)
			(fill no)
			(layer "B.CrtYd")
		)
		(fp_line
			(start 0.508 -0.3048)
			(end 0.508 0.3048)
			(stroke
				(width 0.1)
				(type default)
			)
			(layer "B.Fab")
		)
		(fp_line
			(start -0.508 -0.3048)
			(end 0.508 -0.3048)
			(stroke
				(width 0.1)
				(type default)
			)
			(layer "B.Fab")
		)
		(fp_line
			(start 0.508 0.3048)
			(end -0.508 0.3048)
			(stroke
				(width 0.1)
				(type default)
			)
			(layer "B.Fab")
		)
		(fp_line
			(start -0.508 0.3048)
			(end -0.508 -0.3048)
			(stroke
				(width 0.1)
				(type default)
			)
			(layer "B.Fab")
		)
		(pad "1" smd rect
			(at 0.5334 0 270)
			(size 0.7112 0.6096)
			(layers "B.Cu" "B.Mask" "B.Paste")
			(net "FPGA_IN_MAC_PPS_OUTN")
		)
		(pad "2" smd rect
			(at -0.5334 0 270)
			(size 0.7112 0.6096)
			(layers "B.Cu" "B.Mask" "B.Paste")
			(net "SG")
		)
		(zone
			(layer "B.Cu")
			(hatch none 0.5)
			(connect_pads
				(clearance 0)
			)
			(min_thickness 0.25)
			(keepout
				(tracks not_allowed)
				(vias allowed)
				(pads allowed)
				(copperpour not_allowed)
				(footprints allowed)
			)
			(placement
				(enabled no)
				(sheetname "")
			)
			(fill
				(thermal_gap 0.5)
				(thermal_bridge_width 0.5)
				(island_removal_mode 0)
			)
			(polygon
				(pts
					(xy 116.7638 -29.5402) (xy 116.1542 -29.5402) (xy 116.1542 -29.3878) (xy 116.7638 -29.3878)
				)
			)
		)
		(zone
			(layer "B.Cu")
			(hatch none 0.5)
			(connect_pads
				(clearance 0)
			)
			(min_thickness 0.25)
			(keepout
				(tracks allowed)
				(vias not_allowed)
				(pads allowed)
				(copperpour not_allowed)
				(footprints allowed)
			)
			(placement
				(enabled no)
				(sheetname "")
			)
			(fill
				(thermal_gap 0.5)
				(thermal_bridge_width 0.5)
				(island_removal_mode 0)
			)
			(polygon
				(pts
					(xy 116.7638 -29.5402) (xy 116.1542 -29.5402) (xy 116.1542 -29.3878) (xy 116.7638 -29.3878)
				)
			)
		)
	)
)
